# T6G (Grand Teton) — schematic netlist excerpt (pin names and nets, part order shuffled) for the footprints in the layout excerpt that follows; sources: Cadence DE-HDL packaged netlist, KiCad conversion of 04192023_DAF0TMB3IC0_F0TG_MB_C_brd_V02_OCP.brd

C6004  Q_CAP  0.1UF 25V 10% X7R  pkg 0402  page 180 : A = USB3_CPU0_BMC_TX_DN ; B = USB3_CPU0_BMC_TX_C1_DN
R6304  Q_RES  0 5% CHIP  pkg 0402LF  page 179 : A = USB_HUB2_TI_HS_SUSPEND ; B = USB_HUB2_TI_HS_SUSPEND_MRP_CFG_NON_REM

(kicad_pcb
	(version 20260206)
	(generator "pcbnew")
	(generator_version "10.0")
	(general
		(thickness 1.6)
		(legacy_teardrops no)
	)
	(paper "A4")
	(title_block
		(title "04192023_DAF0TMB3IC0_F0TG_MB_C_brd_V02_OCP.brd")
		(comment 1 "Grand Teton / footprints 4824-4825 of 8354")
	)
	(layers
		(0 "F.Cu" signal "TOP")
		(4 "In1.Cu" signal "GND")
		(6 "In2.Cu" signal "IN1")
		(8 "In3.Cu" signal "GND1")
		(10 "In4.Cu" signal "IN2")
		(12 "In5.Cu" signal "GND2")
		(14 "In6.Cu" signal "IN3")
		(16 "In7.Cu" signal "GND3")
		(18 "In8.Cu" signal "VCC")
		(20 "In9.Cu" signal "VCC1")
		(22 "In10.Cu" signal "GND4")
		(24 "In11.Cu" signal "IN4")
		(26 "In12.Cu" signal "GND5")
		(28 "In13.Cu" signal "IN5")
		(30 "In14.Cu" signal "GND6")
		(32 "In15.Cu" signal "IN6")
		(34 "In16.Cu" signal "GND7")
		(2 "B.Cu" signal "BOTTOM")
		(9 "F.Adhes" user "F.Adhesive")
		(11 "B.Adhes" user "B.Adhesive")
		(13 "F.Paste" user "Package Geometry/Pastemask Top")
		(15 "B.Paste" user "Package Geometry/Pastemask Bottom")
		(5 "F.SilkS" user "Ref Des/Silkscreen Top")
		(7 "B.SilkS" user "Ref Des/Silkscreen Bottom")
		(1 "F.Mask" user "Board Geometry/Soldermask Top")
		(3 "B.Mask" user "Board Geometry/Soldermask Bottom")
		(17 "Dwgs.User" user "User.Drawings")
		(19 "Cmts.User" user "User.Comments")
		(21 "Eco1.User" user "User.Eco1")
		(23 "Eco2.User" user "User.Eco2")
		(25 "Edge.Cuts" user "Board Geometry/Outline")
		(27 "Margin" user)
		(31 "F.CrtYd" user "Package Geometry/Place Bound Top")
		(29 "B.CrtYd" user "Package Geometry/Place Bound Bottom")
		(35 "F.Fab" user "Ref Des/Assembly Top")
		(33 "B.Fab" user "Ref Des/Assembly Bottom")
	)
	(footprint ""
		(layer "F.Cu")
		(at 110.565946 -52.86248 -90)
		(property "Reference" "R6304"
			(at 0 0 270)
			(layer "F.SilkS")
			(hide yes)
			(effects
				(font
					(size 1.27 1.27)
				)
			)
		)
		(property "Value" ""
			(at 0 0 270)
			(layer "F.Fab")
			(effects
				(font
					(size 1.27 1.27)
				)
			)
		)
		(duplicate_pad_numbers_are_jumpers no)
		(fp_line
			(start -0.7874 0.4064)
			(end -0.7874 -0.4064)
			(stroke
				(width 0.1524)
				(type default)
			)
			(layer "F.SilkS")
		)
		(fp_line
			(start 0.7874 0.4064)
			(end -0.7874 0.4064)
			(stroke
				(width 0.1524)
				(type default)
			)
			(layer "F.SilkS")
		)
		(fp_line
			(start -0.7874 -0.4064)
			(end 0.7874 -0.4064)
			(stroke
				(width 0.1524)
				(type default)
			)
			(layer "F.SilkS")
		)
		(fp_line
			(start 0.7874 -0.4064)
			(end 0.7874 0.4064)
			(stroke
				(width 0.1524)
				(type default)
			)
			(layer "F.SilkS")
		)
		(fp_line
			(start -0.67945 0.3048)
			(end -0.67945 -0.305054)
			(stroke
				(width 0.1)
				(type default)
			)
			(layer "F.Fab")
		)
		(fp_line
			(start -0.12065 0.3048)
			(end -0.67945 0.3048)
			(stroke
				(width 0.1)
				(type default)
			)
			(layer "F.Fab")
		)
		(fp_line
			(start 0.120396 0.3048)
			(end 0.120396 0.2794)
			(stroke
				(width 0.1)
				(type default)
			)
			(layer "F.Fab")
		)
		(fp_line
			(start 0.67945 0.3048)
			(end 0.120396 0.3048)
			(stroke
				(width 0.1)
				(type default)
			)
			(layer "F.Fab")
		)
		(fp_line
			(start -0.12065 0.2794)
			(end -0.12065 0.3048)
			(stroke
				(width 0.1)
				(type default)
			)
			(layer "F.Fab")
		)
		(fp_line
			(start 0.120396 0.2794)
			(end -0.12065 0.2794)
			(stroke
				(width 0.1)
				(type default)
			)
			(layer "F.Fab")
		)
		(fp_line
			(start -0.12065 -0.2794)
			(end 0.12065 -0.2794)
			(stroke
				(width 0.1)
				(type default)
			)
			(layer "F.Fab")
		)
		(fp_line
			(start 0.12065 -0.2794)
			(end 0.12065 -0.3048)
			(stroke
				(width 0.1)
				(type default)
			)
			(layer "F.Fab")
		)
		(fp_line
			(start 0.12065 -0.3048)
			(end 0.67945 -0.3048)
			(stroke
				(width 0.1)
				(type default)
			)
			(layer "F.Fab")
		)
		(fp_line
			(start 0.67945 -0.3048)
			(end 0.67945 0.3048)
			(stroke
				(width 0.1)
				(type default)
			)
			(layer "F.Fab")
		)
		(fp_line
			(start -0.67945 -0.305054)
			(end -0.12065 -0.305054)
			(stroke
				(width 0.1)
				(type default)
			)
			(layer "F.Fab")
		)
		(fp_line
			(start -0.12065 -0.305054)
			(end -0.12065 -0.2794)
			(stroke
				(width 0.1)
				(type default)
			)
			(layer "F.Fab")
		)
		(pad "1" smd circle
			(at -0.40005 0 270)
			(size 0 0)
			(layers "F.Cu" "F.Mask" "F.Paste")
			(net "USB_HUB2_TI_HS_SUSPEND")
		)
		(pad "2" smd circle
			(at 0.40005 0 270)
			(size 0 0)
			(layers "F.Cu" "F.Mask" "F.Paste")
			(net "USB_HUB2_TI_HS_SUSPEND_MRP_CFG_NON_REM")
		)
	)
	(footprint ""
		(layer "F.Cu")
		(at 144.36344 -31.58744 90)
		(property "Reference" "C6004"
			(at 0 0 90)
			(layer "F.SilkS")
			(hide yes)
			(effects
				(font
					(size 1.27 1.27)
				)
			)
		)
		(property "Value" ""
			(at 0 0 90)
			(layer "F.Fab")
			(effects
				(font
					(size 1.27 1.27)
				)
			)
		)
		(duplicate_pad_numbers_are_jumpers no)
		(fp_line
			(start 0.7874 -0.4064)
			(end 0.7874 0.4064)
			(stroke
				(width 0.1524)
				(type default)
			)
			(layer "F.SilkS")
		)
		(fp_line
			(start -0.7874 -0.4064)
			(end 0.7874 -0.4064)
			(stroke
				(width 0.1524)
				(type default)
			)
			(layer "F.SilkS")
		)
		(fp_line
			(start 0.7874 0.4064)
			(end -0.7874 0.4064)
			(stroke
				(width 0.1524)
				(type default)
			)
			(layer "F.SilkS")
		)
		(fp_line
			(start -0.7874 0.4064)
			(end -0.7874 -0.4064)
			(stroke
				(width 0.1524)
				(type default)
			)
			(layer "F.SilkS")
		)
		(fp_line
			(start 0.6858 -0.3048)
			(end 0.6858 0.3048)
			(stroke
				(width 0.1)
				(type default)
			)
			(layer "F.Fab")
		)
		(fp_line
			(start 0.1016 -0.3048)
			(end 0.6858 -0.3048)
			(stroke
				(width 0.1)
				(type default)
			)
			(layer "F.Fab")
		)
		(fp_line
			(start -0.1016 -0.3048)
			(end -0.1016 -0.2794)
			(stroke
				(width 0.1)
				(type default)
			)
			(layer "F.Fab")
		)
		(fp_line
			(start -0.6858 -0.3048)
			(end -0.1016 -0.3048)
			(stroke
				(width 0.1)
				(type default)
			)
			(layer "F.Fab")
		)
		(fp_line
			(start 0.1016 -0.2794)
			(end 0.1016 -0.3048)
			(stroke
				(width 0.1)
				(type default)
			)
			(layer "F.Fab")
		)
		(fp_line
			(start -0.1016 -0.2794)
			(end 0.1016 -0.2794)
			(stroke
				(width 0.1)
				(type default)
			)
			(layer "F.Fab")
		)
		(fp_line
			(start 0.1016 0.2794)
			(end -0.1016 0.2794)
			(stroke
				(width 0.1)
				(type default)
			)
			(layer "F.Fab")
		)
		(fp_line
			(start -0.1016 0.2794)
			(end -0.1016 0.3048)
			(stroke
				(width 0.1)
				(type default)
			)
			(layer "F.Fab")
		)
		(fp_line
			(start 0.6858 0.3048)
			(end 0.1016 0.3048)
			(stroke
				(width 0.1)
				(type default)
			)
			(layer "F.Fab")
		)
		(fp_line
			(start 0.1016 0.3048)
			(end 0.1016 0.2794)
			(stroke
				(width 0.1)
				(type default)
			)
			(layer "F.Fab")
		)
		(fp_line
			(start -0.1016 0.3048)
			(end -0.6858 0.3048)
			(stroke
				(width 0.1)
				(type default)
			)
			(layer "F.Fab")
		)
		(fp_line
			(start -0.6858 0.3048)
			(end -0.6858 -0.3048)
			(stroke
				(width 0.1)
				(type default)
			)
			(layer "F.Fab")
		)
		(pad "1" smd rect
			(at -0.40005 0 270)
			(size 0.4572 0.508)
			(layers "F.Cu" "F.Mask" "F.Paste")
			(net "USB3_CPU0_BMC_TX_DN")
		)
		(pad "2" smd rect
			(at 0.40005 0 270)
			(size 0.4572 0.508)
			(layers "F.Cu" "F.Mask" "F.Paste")
			(net "USB3_CPU0_BMC_TX_C1_DN")
		)
	)
)
